# T6G (Grand Teton) — schematic netlist excerpt (pin names and nets, part order shuffled) for the footprints in the layout excerpt that follows; sources: Cadence DE-HDL packaged netlist, KiCad conversion of 04192023_DAF0TMB3IC0_F0TG_MB_C_brd_V02_OCP.brd

R1487  Q_RES  0 5% CHIP  pkg 0402LF  page 135 : A = P12V_OCP_SFF_BUF_EN_R ; B = P3V3_OCP_EN_1_R2
R3442  Q_RES  0 5% CHIP  pkg 0402LF  page 123 : A = GPU_PEX_STRAP0 ; B = GND

(kicad_pcb
	(version 20260206)
	(generator "pcbnew")
	(generator_version "10.0")
	(general
		(thickness 1.6)
		(legacy_teardrops no)
	)
	(paper "A4")
	(title_block
		(title "04192023_DAF0TMB3IC0_F0TG_MB_C_brd_V02_OCP.brd")
		(comment 1 "Grand Teton / footprints 2535-2536 of 8354")
	)
	(layers
		(0 "F.Cu" signal "TOP")
		(4 "In1.Cu" signal "GND")
		(6 "In2.Cu" signal "IN1")
		(8 "In3.Cu" signal "GND1")
		(10 "In4.Cu" signal "IN2")
		(12 "In5.Cu" signal "GND2")
		(14 "In6.Cu" signal "IN3")
		(16 "In7.Cu" signal "GND3")
		(18 "In8.Cu" signal "VCC")
		(20 "In9.Cu" signal "VCC1")
		(22 "In10.Cu" signal "GND4")
		(24 "In11.Cu" signal "IN4")
		(26 "In12.Cu" signal "GND5")
		(28 "In13.Cu" signal "IN5")
		(30 "In14.Cu" signal "GND6")
		(32 "In15.Cu" signal "IN6")
		(34 "In16.Cu" signal "GND7")
		(2 "B.Cu" signal "BOTTOM")
		(9 "F.Adhes" user "F.Adhesive")
		(11 "B.Adhes" user "B.Adhesive")
		(13 "F.Paste" user "Package Geometry/Pastemask Top")
		(15 "B.Paste" user "Package Geometry/Pastemask Bottom")
		(5 "F.SilkS" user "Ref Des/Silkscreen Top")
		(7 "B.SilkS" user "Ref Des/Silkscreen Bottom")
		(1 "F.Mask" user "Board Geometry/Soldermask Top")
		(3 "B.Mask" user "Board Geometry/Soldermask Bottom")
		(17 "Dwgs.User" user "User.Drawings")
		(19 "Cmts.User" user "User.Comments")
		(21 "Eco1.User" user "User.Eco1")
		(23 "Eco2.User" user "User.Eco2")
		(25 "Edge.Cuts" user "Board Geometry/Outline")
		(27 "Margin" user)
		(31 "F.CrtYd" user "Package Geometry/Place Bound Top")
		(29 "B.CrtYd" user "Package Geometry/Place Bound Bottom")
		(35 "F.Fab" user "Ref Des/Assembly Top")
		(33 "B.Fab" user "Ref Des/Assembly Bottom")
	)
	(footprint ""
		(layer "F.Cu")
		(at 419.10889 -109.231176 -90)
		(property "Reference" "R1487"
			(at 0 0 270)
			(layer "F.SilkS")
			(hide yes)
			(effects
				(font
					(size 1.27 1.27)
				)
			)
		)
		(property "Value" ""
			(at 0 0 270)
			(layer "F.Fab")
			(effects
				(font
					(size 1.27 1.27)
				)
			)
		)
		(duplicate_pad_numbers_are_jumpers no)
		(fp_line
			(start -0.7874 0.4064)
			(end -0.7874 -0.4064)
			(stroke
				(width 0.1524)
				(type default)
			)
			(layer "F.SilkS")
		)
		(fp_line
			(start 0.7874 0.4064)
			(end -0.7874 0.4064)
			(stroke
				(width 0.1524)
				(type default)
			)
			(layer "F.SilkS")
		)
		(fp_line
			(start -0.7874 -0.4064)
			(end 0.7874 -0.4064)
			(stroke
				(width 0.1524)
				(type default)
			)
			(layer "F.SilkS")
		)
		(fp_line
			(start 0.7874 -0.4064)
			(end 0.7874 0.4064)
			(stroke
				(width 0.1524)
				(type default)
			)
			(layer "F.SilkS")
		)
		(fp_line
			(start -0.67945 0.3048)
			(end -0.67945 -0.305054)
			(stroke
				(width 0.1)
				(type default)
			)
			(layer "F.Fab")
		)
		(fp_line
			(start -0.12065 0.3048)
			(end -0.67945 0.3048)
			(stroke
				(width 0.1)
				(type default)
			)
			(layer "F.Fab")
		)
		(fp_line
			(start 0.120396 0.3048)
			(end 0.120396 0.2794)
			(stroke
				(width 0.1)
				(type default)
			)
			(layer "F.Fab")
		)
		(fp_line
			(start 0.67945 0.3048)
			(end 0.120396 0.3048)
			(stroke
				(width 0.1)
				(type default)
			)
			(layer "F.Fab")
		)
		(fp_line
			(start -0.12065 0.2794)
			(end -0.12065 0.3048)
			(stroke
				(width 0.1)
				(type default)
			)
			(layer "F.Fab")
		)
		(fp_line
			(start 0.120396 0.2794)
			(end -0.12065 0.2794)
			(stroke
				(width 0.1)
				(type default)
			)
			(layer "F.Fab")
		)
		(fp_line
			(start -0.12065 -0.2794)
			(end 0.12065 -0.2794)
			(stroke
				(width 0.1)
				(type default)
			)
			(layer "F.Fab")
		)
		(fp_line
			(start 0.12065 -0.2794)
			(end 0.12065 -0.3048)
			(stroke
				(width 0.1)
				(type default)
			)
			(layer "F.Fab")
		)
		(fp_line
			(start 0.12065 -0.3048)
			(end 0.67945 -0.3048)
			(stroke
				(width 0.1)
				(type default)
			)
			(layer "F.Fab")
		)
		(fp_line
			(start 0.67945 -0.3048)
			(end 0.67945 0.3048)
			(stroke
				(width 0.1)
				(type default)
			)
			(layer "F.Fab")
		)
		(fp_line
			(start -0.67945 -0.305054)
			(end -0.12065 -0.305054)
			(stroke
				(width 0.1)
				(type default)
			)
			(layer "F.Fab")
		)
		(fp_line
			(start -0.12065 -0.305054)
			(end -0.12065 -0.2794)
			(stroke
				(width 0.1)
				(type default)
			)
			(layer "F.Fab")
		)
		(pad "1" smd circle
			(at -0.40005 0 270)
			(size 0 0)
			(layers "F.Cu" "F.Mask" "F.Paste")
			(net "P12V_OCP_SFF_BUF_EN_R")
		)
		(pad "2" smd circle
			(at 0.40005 0 270)
			(size 0 0)
			(layers "F.Cu" "F.Mask" "F.Paste")
			(net "P3V3_OCP_EN_1_R2")
		)
	)
	(footprint ""
		(layer "F.Cu")
		(at 186.038236 -428.414942 90)
		(property "Reference" "R3442"
			(at 0 0 90)
			(layer "F.SilkS")
			(hide yes)
			(effects
				(font
					(size 1.27 1.27)
				)
			)
		)
		(property "Value" ""
			(at 0 0 90)
			(layer "F.Fab")
			(effects
				(font
					(size 1.27 1.27)
				)
			)
		)
		(duplicate_pad_numbers_are_jumpers no)
		(fp_line
			(start 0.7874 -0.4064)
			(end 0.7874 0.4064)
			(stroke
				(width 0.1524)
				(type default)
			)
			(layer "F.SilkS")
		)
		(fp_line
			(start -0.7874 -0.4064)
			(end 0.7874 -0.4064)
			(stroke
				(width 0.1524)
				(type default)
			)
			(layer "F.SilkS")
		)
		(fp_line
			(start 0.7874 0.4064)
			(end -0.7874 0.4064)
			(stroke
				(width 0.1524)
				(type default)
			)
			(layer "F.SilkS")
		)
		(fp_line
			(start -0.7874 0.4064)
			(end -0.7874 -0.4064)
			(stroke
				(width 0.1524)
				(type default)
			)
			(layer "F.SilkS")
		)
		(fp_line
			(start -0.12065 -0.305054)
			(end -0.12065 -0.2794)
			(stroke
				(width 0.1)
				(type default)
			)
			(layer "F.Fab")
		)
		(fp_line
			(start -0.67945 -0.305054)
			(end -0.12065 -0.305054)
			(stroke
				(width 0.1)
				(type default)
			)
			(layer "F.Fab")
		)
		(fp_line
			(start 0.67945 -0.3048)
			(end 0.67945 0.3048)
			(stroke
				(width 0.1)
				(type default)
			)
			(layer "F.Fab")
		)
		(fp_line
			(start 0.12065 -0.3048)
			(end 0.67945 -0.3048)
			(stroke
				(width 0.1)
				(type default)
			)
			(layer "F.Fab")
		)
		(fp_line
			(start 0.12065 -0.2794)
			(end 0.12065 -0.3048)
			(stroke
				(width 0.1)
				(type default)
			)
			(layer "F.Fab")
		)
		(fp_line
			(start -0.12065 -0.2794)
			(end 0.12065 -0.2794)
			(stroke
				(width 0.1)
				(type default)
			)
			(layer "F.Fab")
		)
		(fp_line
			(start 0.120396 0.2794)
			(end -0.12065 0.2794)
			(stroke
				(width 0.1)
				(type default)
			)
			(layer "F.Fab")
		)
		(fp_line
			(start -0.12065 0.2794)
			(end -0.12065 0.3048)
			(stroke
				(width 0.1)
				(type default)
			)
			(layer "F.Fab")
		)
		(fp_line
			(start 0.67945 0.3048)
			(end 0.120396 0.3048)
			(stroke
				(width 0.1)
				(type default)
			)
			(layer "F.Fab")
		)
		(fp_line
			(start 0.120396 0.3048)
			(end 0.120396 0.2794)
			(stroke
				(width 0.1)
				(type default)
			)
			(layer "F.Fab")
		)
		(fp_line
			(start -0.12065 0.3048)
			(end -0.67945 0.3048)
			(stroke
				(width 0.1)
				(type default)
			)
			(layer "F.Fab")
		)
		(fp_line
			(start -0.67945 0.3048)
			(end -0.67945 -0.305054)
			(stroke
				(width 0.1)
				(type default)
			)
			(layer "F.Fab")
		)
		(pad "1" smd circle
			(at -0.40005 0 90)
			(size 0 0)
			(layers "F.Cu" "F.Mask" "F.Paste")
			(net "GPU_PEX_STRAP0")
		)
		(pad "2" smd circle
			(at 0.40005 0 90)
			(size 0 0)
			(layers "F.Cu" "F.Mask" "F.Paste")
			(net "GND")
		)
	)
)
